# SCM (Grand Teton) — schematic netlist excerpt (pin names and nets, part order shuffled) for the footprints in the layout excerpt that follows; sources: Cadence DE-HDL packaged netlist, KiCad conversion of 12092022_DA0F0TMDCD0_F0T_Management_Board_D_brd_V3_OCP.brd

C263  Q_CAP  0.1UF 25V 10% X7R  pkg 0402  page 41 : A = PVCCA_AUX_PLD ; B = GND
R111  Q_RES  33.2 1% CHIP  pkg 0402LF  page 13 : A = FM_BMC_READY_R_PLD_N ; B = FM_BMC_READY_PLD_N

(kicad_pcb
	(version 20260206)
	(generator "pcbnew")
	(generator_version "10.0")
	(general
		(thickness 1.6)
		(legacy_teardrops no)
	)
	(paper "A4")
	(title_block
		(title "12092022_DA0F0TMDCD0_F0T_Management_Board_D_brd_V3_OCP.brd")
		(comment 1 "Grand Teton / footprints 982-983 of 1440")
	)
	(layers
		(0 "F.Cu" signal "TOP")
		(4 "In1.Cu" signal "GND")
		(6 "In2.Cu" signal "IN1")
		(8 "In3.Cu" signal "GND1")
		(10 "In4.Cu" signal "IN2")
		(12 "In5.Cu" signal "VCC")
		(14 "In6.Cu" signal "VCC1")
		(16 "In7.Cu" signal "IN3")
		(18 "In8.Cu" signal "GND2")
		(20 "In9.Cu" signal "IN4")
		(22 "In10.Cu" signal "GND3")
		(2 "B.Cu" signal "BOTTOM")
		(9 "F.Adhes" user "F.Adhesive")
		(11 "B.Adhes" user "B.Adhesive")
		(13 "F.Paste" user "Package Geometry/Pastemask Top")
		(15 "B.Paste" user "Package Geometry/Pastemask Bottom")
		(5 "F.SilkS" user "Ref Des/Silkscreen Top")
		(7 "B.SilkS" user "Ref Des/Silkscreen Bottom")
		(1 "F.Mask" user "Board Geometry/Soldermask Top")
		(3 "B.Mask" user "Board Geometry/Soldermask Bottom")
		(17 "Dwgs.User" user "User.Drawings")
		(19 "Cmts.User" user "User.Comments")
		(21 "Eco1.User" user "User.Eco1")
		(23 "Eco2.User" user "User.Eco2")
		(25 "Edge.Cuts" user "Board Geometry/Outline")
		(27 "Margin" user)
		(31 "F.CrtYd" user "Package Geometry/Place Bound Top")
		(29 "B.CrtYd" user "Package Geometry/Place Bound Bottom")
		(35 "F.Fab" user "Ref Des/Assembly Top")
		(33 "B.Fab" user "Ref Des/Assembly Bottom")
	)
	(footprint ""
		(layer "B.Cu")
		(at 47.4218 -76.2762)
		(property "Reference" "R111"
			(at 0 0 0)
			(layer "B.SilkS")
			(hide yes)
			(effects
				(font
					(size 1.27 1.27)
				)
				(justify mirror)
			)
		)
		(property "Value" ""
			(at 0 0 0)
			(layer "B.Fab")
			(effects
				(font
					(size 1.27 1.27)
				)
				(justify mirror)
			)
		)
		(duplicate_pad_numbers_are_jumpers no)
		(fp_line
			(start -0.7874 -0.4064)
			(end -0.7874 0.4064)
			(stroke
				(width 0.1524)
				(type default)
			)
			(layer "B.SilkS")
		)
		(fp_line
			(start -0.7874 0.4064)
			(end 0.7874 0.4064)
			(stroke
				(width 0.1524)
				(type default)
			)
			(layer "B.SilkS")
		)
		(fp_line
			(start 0.7874 -0.4064)
			(end -0.7874 -0.4064)
			(stroke
				(width 0.1524)
				(type default)
			)
			(layer "B.SilkS")
		)
		(fp_line
			(start 0.7874 0.4064)
			(end 0.7874 -0.4064)
			(stroke
				(width 0.1524)
				(type default)
			)
			(layer "B.SilkS")
		)
		(fp_line
			(start -0.67945 -0.3048)
			(end -0.67945 0.3048)
			(stroke
				(width 0.1)
				(type default)
			)
			(layer "B.Fab")
		)
		(fp_line
			(start -0.67945 0.3048)
			(end -0.120396 0.3048)
			(stroke
				(width 0.1)
				(type default)
			)
			(layer "B.Fab")
		)
		(fp_line
			(start -0.12065 -0.3048)
			(end -0.67945 -0.3048)
			(stroke
				(width 0.1)
				(type default)
			)
			(layer "B.Fab")
		)
		(fp_line
			(start -0.12065 -0.2794)
			(end -0.12065 -0.3048)
			(stroke
				(width 0.1)
				(type default)
			)
			(layer "B.Fab")
		)
		(fp_line
			(start -0.120396 0.2794)
			(end 0.12065 0.2794)
			(stroke
				(width 0.1)
				(type default)
			)
			(layer "B.Fab")
		)
		(fp_line
			(start -0.120396 0.3048)
			(end -0.120396 0.2794)
			(stroke
				(width 0.1)
				(type default)
			)
			(layer "B.Fab")
		)
		(fp_line
			(start 0.12065 -0.305054)
			(end 0.12065 -0.2794)
			(stroke
				(width 0.1)
				(type default)
			)
			(layer "B.Fab")
		)
		(fp_line
			(start 0.12065 -0.2794)
			(end -0.12065 -0.2794)
			(stroke
				(width 0.1)
				(type default)
			)
			(layer "B.Fab")
		)
		(fp_line
			(start 0.12065 0.2794)
			(end 0.12065 0.3048)
			(stroke
				(width 0.1)
				(type default)
			)
			(layer "B.Fab")
		)
		(fp_line
			(start 0.12065 0.3048)
			(end 0.67945 0.3048)
			(stroke
				(width 0.1)
				(type default)
			)
			(layer "B.Fab")
		)
		(fp_line
			(start 0.67945 -0.305054)
			(end 0.12065 -0.305054)
			(stroke
				(width 0.1)
				(type default)
			)
			(layer "B.Fab")
		)
		(fp_line
			(start 0.67945 0.3048)
			(end 0.67945 -0.305054)
			(stroke
				(width 0.1)
				(type default)
			)
			(layer "B.Fab")
		)
		(pad "1" smd circle
			(at 0.40005 0 180)
			(size 0 0)
			(layers "B.Cu" "B.Mask" "B.Paste")
			(net "FM_BMC_READY_R_PLD_N")
		)
		(pad "2" smd circle
			(at -0.40005 0 180)
			(size 0 0)
			(layers "B.Cu" "B.Mask" "B.Paste")
			(net "FM_BMC_READY_PLD_N")
		)
	)
	(footprint ""
		(layer "B.Cu")
		(at 24.202644 -95.130112 180)
		(property "Reference" "C263"
			(at 0 0 0)
			(layer "B.SilkS")
			(hide yes)
			(effects
				(font
					(size 1.27 1.27)
				)
				(justify mirror)
			)
		)
		(property "Value" ""
			(at 0 0 0)
			(layer "B.Fab")
			(effects
				(font
					(size 1.27 1.27)
				)
				(justify mirror)
			)
		)
		(duplicate_pad_numbers_are_jumpers no)
		(fp_line
			(start 0.69215 0.2921)
			(end 0.69215 -0.2921)
			(stroke
				(width 0.1524)
				(type default)
			)
			(layer "B.SilkS")
		)
		(fp_line
			(start 0.69215 -0.2921)
			(end -0.69215 -0.2921)
			(stroke
				(width 0.1524)
				(type default)
			)
			(layer "B.SilkS")
		)
		(fp_line
			(start -0.69215 0.2921)
			(end 0.69215 0.2921)
			(stroke
				(width 0.1524)
				(type default)
			)
			(layer "B.SilkS")
		)
		(fp_line
			(start -0.69215 -0.2921)
			(end -0.69215 0.2921)
			(stroke
				(width 0.1524)
				(type default)
			)
			(layer "B.SilkS")
		)
		(fp_line
			(start 0.51435 0.2794)
			(end 0.51435 -0.2794)
			(stroke
				(width 0.1)
				(type default)
			)
			(layer "B.Fab")
		)
		(fp_line
			(start 0.51435 -0.2794)
			(end -0.51435 -0.2794)
			(stroke
				(width 0.1)
				(type default)
			)
			(layer "B.Fab")
		)
		(fp_line
			(start -0.51435 0.2794)
			(end 0.51435 0.2794)
			(stroke
				(width 0.1)
				(type default)
			)
			(layer "B.Fab")
		)
		(fp_line
			(start -0.51435 -0.2794)
			(end -0.51435 0.2794)
			(stroke
				(width 0.1)
				(type default)
			)
			(layer "B.Fab")
		)
		(pad "1" smd circle
			(at 0.40005 0)
			(size 0 0)
			(layers "B.Cu" "B.Mask" "B.Paste")
			(net "PVCCA_AUX_PLD")
		)
		(pad "2" smd circle
			(at -0.40005 0)
			(size 0 0)
			(layers "B.Cu" "B.Mask" "B.Paste")
			(net "GND")
		)
		(zone
			(layer "B.Cu")
			(hatch none 0.5)
			(connect_pads
				(clearance 0)
			)
			(min_thickness 0.25)
			(keepout
				(tracks not_allowed)
				(vias allowed)
				(pads allowed)
				(copperpour not_allowed)
				(footprints allowed)
			)
			(placement
				(enabled no)
				(sheetname "")
			)
			(fill
				(thermal_gap 0.5)
				(thermal_bridge_width 0.5)
				(island_removal_mode 0)
			)
			(polygon
				(pts
					(xy 24.012144 -95.217742) (xy 24.103584 -95.275908) (xy 24.302974 -95.275908) (xy 24.393144 -95.217742)
					(xy 24.393144 -95.042482) (xy 24.302974 -94.984062) (xy 24.103584 -94.984062) (xy 24.012144 -95.042228)
				)
			)
		)
	)
)
